# T6G (Grand Teton) — schematic parts with pin connectivity, parts 3804–3898 of 8303; source: Cadence DE-HDL packaged netlist (pstxprt.dat, pstxnet.dat, pstchip.dat)

PL10  Q_INDUCTOR4P_14  150NH IND  pkg L_TLM117513Q-151QL_11X7-5XA  page 201
  1  \1\  BI  = SW_PVDDCR_CPU1_P0_SW1
  2  \2\  BI  = IND_CPU1_P0_CPL5
  3  \3\  BI  = IND_CPU1_P0_CPL1
  4  \4\  BI  = PVDDCR_CPU1_P0

PL11  Q_INDUCTOR4P_14  150NH IND  pkg L_TLM117513Q-151QL_11X7-5XA  page 201
  1  \1\  BI  = SW_PVDDCR_CPU1_P0_SW2
  2  \2\  BI  = IND_CPU1_P0_CPL1
  3  \3\  BI  = IND_CPU1_P0_CPL2
  4  \4\  BI  = PVDDCR_CPU1_P0

PL12  Q_INDUCTOR  50NH/86A IND  pkg SMLF  page 201 : 1 = SW_P12V_AUX_PVDDCR_CPU1_P0_FLT ; 2 = P12V_AUX

PL13  Q_INDUCTOR4P_14  150NH IND  pkg L_TLM117513Q-151QL_11X7-5XA  page 202
  1  \1\  BI  = SW_PVDDCR_CPU1_P0_SW4
  2  \2\  BI  = IND_CPU1_P0_CPL3
  3  \3\  BI  = GND
  4  \4\  BI  = PVDDCR_CPU1_P0

PL14  Q_INDUCTOR4P_14  150NH IND  pkg L_TLM117513Q-151QL_11X7-5XA  page 202
  1  \1\  BI  = SW_PVDDCR_CPU1_P0_SW3
  2  \2\  BI  = IND_CPU1_P0_CPL2
  3  \3\  BI  = IND_CPU1_P0_CPL3
  4  \4\  BI  = PVDDCR_CPU1_P0

PL15  Q_INDUCTOR4P_14  150NH IND  pkg L_TLM117513Q-151QL_11X7-5XA  page 203
  1  \1\  BI  = SW_PVDDCR_CPU1_P0_SW5
  2  \2\  BI  = IND_CPU1_P0_CPL6
  3  \3\  BI  = IND_CPU1_P0_CPL5
  4  \4\  BI  = PVDDCR_CPU1_P0

PL16  Q_INDUCTOR  0.22UH/33A IND  pkg SMLF  page 206 : 1 = IND_PVDDIO_P0_CPL0 ; 2 = GND

PL17  Q_INDUCTOR4P_14  150NH IND  pkg L_TLM117513Q-151QL_11X7-5XA  page 205
  1  \1\  BI  = SW_PVDDIO_P0_SW1
  2  \2\  BI  = IND_PVDDIO_P0_CPL2
  3  \3\  BI  = GND
  4  \4\  BI  = PVDDIO_P0

PL18  Q_INDUCTOR4P_14  150NH IND  pkg L_TLM117513Q-151QL_11X7-5XA  page 205
  1  \1\  BI  = SW_PVDDIO_P0_SW2
  2  \2\  BI  = IND_PVDDIO_P0_CPL3
  3  \3\  BI  = IND_PVDDIO_P0_CPL2
  4  \4\  BI  = PVDDIO_P0

PL19  Q_INDUCTOR  50NH/86A IND  pkg SMLF  page 205 : 1 = SW_P12V_AUX_PVDDIO_P0_FLT ; 2 = P12V_AUX

PL20  Q_INDUCTOR4P_14  150NH IND  pkg L_TLM117513Q-151QL_11X7-5XA  page 206
  1  \1\  BI  = SW_PVDDIO_P0_SW4
  2  \2\  BI  = IND_PVDDIO_P0_CPL0
  3  \3\  BI  = IND_PVDDIO_P0_CPL4
  4  \4\  BI  = PVDDIO_P0

PL21  Q_INDUCTOR4P_14  150NH IND  pkg L_TLM117513Q-151QL_11X7-5XA  page 206
  1  \1\  BI  = SW_PVDDIO_P0_SW3
  2  \2\  BI  = IND_PVDDIO_P0_CPL4
  3  \3\  BI  = IND_PVDDIO_P0_CPL3
  4  \4\  BI  = PVDDIO_P0

PL22  Q_INDUCTOR  90NH/155A IND  pkg SMLF  page 208 : 1 = SW_PVDD11_S3_P0_SW2 ; 2 = PVDD11_S3_P0
PL23  Q_INDUCTOR  90NH/155A IND  pkg SMLF  page 208 : 1 = SW_PVDD11_S3_P0_SW1 ; 2 = PVDD11_S3_P0
PL24  Q_INDUCTOR  100NH/16A IND  pkg SMLF  page 208 : 1 = SW_P12V_AUX_PVDD11_S3_P0_FLT ; 2 = P12V_AUX
PL26  Q_INDUCTOR  BLM18SN220TN1D/8000MA IND  pkg SMLF  page 226 : 1 = P12V_AUX ; 2 = SW_P12V_AUX_PVDD18_S5_P1_FLT
PL27  Q_INDUCTOR  120NH/69A IND  pkg SMLF  page 213 : 1 = GND ; 2 = IND_CPU0_P1_CPL0

PL28  Q_INDUCTOR4P_14  150NH IND  pkg L_TLM117513Q-151QL_11X7-5XA  page 211
  1  \1\  BI  = SW_PVDDCR_CPU0_P1_SW1
  2  \2\  BI  = IND_CPU0_P1_CPL5
  3  \3\  BI  = IND_CPU0_P1_CPL1
  4  \4\  BI  = PVDDCR_CPU0_P1

PL29  Q_INDUCTOR4P_14  150NH IND  pkg L_TLM117513Q-151QL_11X7-5XA  page 211
  1  \1\  BI  = SW_PVDDCR_CPU0_P1_SW2
  2  \2\  BI  = IND_CPU0_P1_CPL1
  3  \3\  BI  = IND_CPU0_P1_CPL2
  4  \4\  BI  = PVDDCR_CPU0_P1

PL30  Q_INDUCTOR  50NH/86A IND  pkg SMLF  page 211 : 1 = SW_P12V_AUX_PVDDCR_CPU0_P1_FLT ; 2 = P12V_AUX

PL31  Q_INDUCTOR4P_14  150NH IND  pkg L_TLM117513Q-151QL_11X7-5XA  page 212
  1  \1\  BI  = SW_PVDDCR_CPU0_P1_SW3
  2  \2\  BI  = IND_CPU0_P1_CPL2
  3  \3\  BI  = IND_CPU0_P1_CPL3
  4  \4\  BI  = PVDDCR_CPU0_P1

PL32  Q_INDUCTOR4P_14  150NH IND  pkg L_TLM117513Q-151QL_11X7-5XA  page 212
  1  \1\  BI  = SW_PVDDCR_CPU0_P1_SW4
  2  \2\  BI  = IND_CPU0_P1_CPL3
  3  \3\  BI  = GND
  4  \4\  BI  = PVDDCR_CPU0_P1

PL33  Q_INDUCTOR4P_14  150NH IND  pkg L_TLM117513Q-151QL_11X7-5XA  page 213
  1  \1\  BI  = SW_PVDDCR_CPU0_P1_SW5
  2  \2\  BI  = IND_CPU0_P1_CPL6
  3  \3\  BI  = IND_CPU0_P1_CPL5
  4  \4\  BI  = PVDDCR_CPU0_P1

PL34  Q_INDUCTOR  0.22UH/33A IND  pkg SMLF  page 216 : 1 = GND ; 2 = IND_SOC_P1_CPL0

PL35  Q_INDUCTOR4P_14  150NH IND  pkg L_TLM117513Q-151QL_11X7-5XA  page 215
  1  \1\  BI  = SW_PVDDCR_SOC_P1_SW1
  2  \2\  BI  = IND_SOC_P1_CPL2
  3  \3\  BI  = GND
  4  \4\  BI  = PVDDCR_SOC_P1

PL36  Q_INDUCTOR4P_14  150NH IND  pkg L_TLM117513Q-151QL_11X7-5XA  page 215
  1  \1\  BI  = SW_PVDDCR_SOC_P1_SW2
  2  \2\  BI  = IND_SOC_P1_CPL3
  3  \3\  BI  = IND_SOC_P1_CPL2
  4  \4\  BI  = PVDDCR_SOC_P1

PL37  Q_INDUCTOR  50NH/86A IND  pkg SMLF  page 215 : 1 = SW_P12V_AUX_PVDDCR_SOC_P1_FLT ; 2 = P12V_AUX

PL38  Q_INDUCTOR4P_14  150NH IND  pkg L_TLM117513Q-151QL_11X7-5XA  page 216
  1  \1\  BI  = SW_PVDDCR_SOC_P1_SW3
  2  \2\  BI  = IND_SOC_P1_CPL0
  3  \3\  BI  = IND_SOC_P1_CPL3
  4  \4\  BI  = PVDDCR_SOC_P1

PL39  Q_INDUCTOR  120NH/69A IND  pkg SMLF  page 220 : 1 = IND_CPU1_P1_CPL0 ; 2 = GND

PL40  Q_INDUCTOR4P_14  150NH IND  pkg L_TLM117513Q-151QL_11X7-5XA  page 218
  1  \1\  BI  = SW_PVDDCR_CPU1_P1_SW1
  2  \2\  BI  = IND_CPU1_P1_CPL5
  3  \3\  BI  = IND_CPU1_P1_CPL1
  4  \4\  BI  = PVDDCR_CPU1_P1

PL41  Q_INDUCTOR4P_14  150NH IND  pkg L_TLM117513Q-151QL_11X7-5XA  page 218
  1  \1\  BI  = SW_PVDDCR_CPU1_P1_SW2
  2  \2\  BI  = IND_CPU1_P1_CPL1
  3  \3\  BI  = IND_CPU1_P1_CPL2
  4  \4\  BI  = PVDDCR_CPU1_P1

PL42  Q_INDUCTOR  50NH/86A IND  pkg SMLF  page 218 : 1 = SW_P12V_AUX_PVDDCR_CPU1_P1_FLT ; 2 = P12V_AUX

PL43  Q_INDUCTOR4P_14  150NH IND  pkg L_TLM117513Q-151QL_11X7-5XA  page 219
  1  \1\  BI  = SW_PVDDCR_CPU1_P1_SW4
  2  \2\  BI  = IND_CPU1_P1_CPL3
  3  \3\  BI  = GND
  4  \4\  BI  = PVDDCR_CPU1_P1

PL44  Q_INDUCTOR4P_14  150NH IND  pkg L_TLM117513Q-151QL_11X7-5XA  page 219
  1  \1\  BI  = SW_PVDDCR_CPU1_P1_SW3
  2  \2\  BI  = IND_CPU1_P1_CPL2
  3  \3\  BI  = IND_CPU1_P1_CPL3
  4  \4\  BI  = PVDDCR_CPU1_P1

PL45  Q_INDUCTOR4P_14  150NH IND  pkg L_TLM117513Q-151QL_11X7-5XA  page 220
  1  \1\  BI  = SW_PVDDCR_CPU1_P1_SW5
  2  \2\  BI  = IND_CPU1_P1_CPL6
  3  \3\  BI  = IND_CPU1_P1_CPL5
  4  \4\  BI  = PVDDCR_CPU1_P1

PL46  Q_INDUCTOR  0.22UH/33A IND  pkg SMLF  page 223 : 1 = IND_PVDDIO_P1_CPL0 ; 2 = GND

PL47  Q_INDUCTOR4P_14  150NH IND  pkg L_TLM117513Q-151QL_11X7-5XA  page 222
  1  \1\  BI  = SW_PVDDIO_P1_SW1
  2  \2\  BI  = IND_PVDDIO_P1_CPL2
  3  \3\  BI  = GND
  4  \4\  BI  = PVDDIO_P1

PL48  Q_INDUCTOR4P_14  150NH IND  pkg L_TLM117513Q-151QL_11X7-5XA  page 222
  1  \1\  BI  = SW_PVDDIO_P1_SW2
  2  \2\  BI  = IND_PVDDIO_P1_CPL3
  3  \3\  BI  = IND_PVDDIO_P1_CPL2
  4  \4\  BI  = PVDDIO_P1

PL49  Q_INDUCTOR  50NH/86A IND  pkg SMLF  page 222 : 1 = SW_P12V_AUX_PVDDIO_P1_FLT ; 2 = P12V_AUX
PL50  Q_INDUCTOR  120NH/69A IND  pkg SMLF  page 196 : 1 = GND ; 2 = IND_CPU0_P0_CPL0

PL51  Q_INDUCTOR4P_14  150NH IND  pkg L_TLM117513Q-151QL_11X7-5XA  page 194
  1  \1\  BI  = SW_PVDDCR_CPU0_P0_SW1
  2  \2\  BI  = IND_CPU0_P0_CPL5
  3  \3\  BI  = IND_CPU0_P0_CPL1
  4  \4\  BI  = PVDDCR_CPU0_P0

PL52  Q_INDUCTOR4P_14  150NH IND  pkg L_TLM117513Q-151QL_11X7-5XA  page 194
  1  \1\  BI  = SW_PVDDCR_CPU0_P0_SW2
  2  \2\  BI  = IND_CPU0_P0_CPL1
  3  \3\  BI  = IND_CPU0_P0_CPL2
  4  \4\  BI  = PVDDCR_CPU0_P0

PL53  Q_INDUCTOR  50NH/86A IND  pkg SMLF  page 194 : 1 = SW_P12V_AUX_PVDDCR_CPU0_P0_FLT ; 2 = P12V_AUX
PL54  Q_INDUCTOR  90NH/155A IND  pkg SMLF  page 225 : 1 = SW_PVDD11_S3_P1_SW1 ; 2 = PVDD11_S3_P1
PL55  Q_INDUCTOR  90NH/155A IND  pkg SMLF  page 225 : 1 = SW_PVDD11_S3_P1_SW2 ; 2 = PVDD11_S3_P1
PL56  Q_INDUCTOR  100NH/16A IND  pkg SMLF  page 225 : 1 = SW_P12V_AUX_PVDD11_S3_P1_FLT ; 2 = P12V_AUX
PL57  Q_INDUCTOR  1.0UH/18A IND  pkg SMLF  page 226 : 1 = SW_PVDD18_S5_P1_SW ; 2 = PVDD18_S5_P1

PL59  Q_INDUCTOR4P_14  150NH IND  pkg L_TLM117513Q-151QL_11X7-5XA  page 195
  1  \1\  BI  = SW_PVDDCR_CPU0_P0_SW3
  2  \2\  BI  = IND_CPU0_P0_CPL2
  3  \3\  BI  = IND_CPU0_P0_CPL3
  4  \4\  BI  = PVDDCR_CPU0_P0

PL60  Q_INDUCTOR4P_14  150NH IND  pkg L_TLM117513Q-151QL_11X7-5XA  page 195
  1  \1\  BI  = SW_PVDDCR_CPU0_P0_SW4
  2  \2\  BI  = IND_CPU0_P0_CPL3
  3  \3\  BI  = GND
  4  \4\  BI  = PVDDCR_CPU0_P0

PL61  Q_INDUCTOR4P_14  150NH IND  pkg L_TLM117513Q-151QL_11X7-5XA  page 196
  1  \1\  BI  = SW_PVDDCR_CPU0_P0_SW5
  2  \2\  BI  = IND_CPU0_P0_CPL6
  3  \3\  BI  = IND_CPU0_P0_CPL5
  4  \4\  BI  = PVDDCR_CPU0_P0

PL62  Q_INDUCTOR  0.22UH/33A IND  pkg SMLF  page 199 : 1 = GND ; 2 = IND_SOC_P0_CPL0

PL63  Q_INDUCTOR4P_14  150NH IND  pkg L_TLM117513Q-151QL_11X7-5XA  page 198
  1  \1\  BI  = SW_PVDDCR_SOC_P0_SW1
  2  \2\  BI  = IND_SOC_P0_CPL2
  3  \3\  BI  = GND
  4  \4\  BI  = PVDDCR_SOC_P0

PL64  Q_INDUCTOR4P_14  150NH IND  pkg L_TLM117513Q-151QL_11X7-5XA  page 198
  1  \1\  BI  = SW_PVDDCR_SOC_P0_SW2
  2  \2\  BI  = IND_SOC_P0_CPL3
  3  \3\  BI  = IND_SOC_P0_CPL2
  4  \4\  BI  = PVDDCR_SOC_P0

PL65  Q_INDUCTOR  50NH/86A IND  pkg SMLF  page 198 : 1 = SW_P12V_AUX_PVDDCR_SOC_P0_FLT ; 2 = P12V_AUX

PL66  Q_INDUCTOR4P_14  150NH IND  pkg L_TLM117513Q-151QL_11X7-5XA  page 199
  1  \1\  BI  = SW_PVDDCR_SOC_P0_SW3
  2  \2\  BI  = IND_SOC_P0_CPL0
  3  \3\  BI  = IND_SOC_P0_CPL3
  4  \4\  BI  = PVDDCR_SOC_P0

PL67  Q_INDUCTOR4P_14  150NH IND  pkg L_TLM117513Q-151QL_11X7-5XA  page 223
  1  \1\  BI  = SW_PVDDIO_P1_SW4
  2  \2\  BI  = IND_PVDDIO_P1_CPL0
  3  \3\  BI  = IND_PVDDIO_P1_CPL4
  4  \4\  BI  = PVDDIO_P1

PL68  Q_INDUCTOR4P_14  150NH IND  pkg L_TLM117513Q-151QL_11X7-5XA  page 223
  1  \1\  BI  = SW_PVDDIO_P1_SW3
  2  \2\  BI  = IND_PVDDIO_P1_CPL4
  3  \3\  BI  = IND_PVDDIO_P1_CPL3
  4  \4\  BI  = PVDDIO_P1

PL69  Q_INDUCTOR4P_14  150NH IND  pkg L_TLM117513Q-151QL_11X7-5XA  page 220
  1  \1\  BI  = SW_PVDDCR_CPU1_P1_SW6
  2  \2\  BI  = IND_CPU1_P1_CPL0
  3  \3\  BI  = IND_CPU1_P1_CPL6
  4  \4\  BI  = PVDDCR_CPU1_P1

PL70  Q_INDUCTOR4P_14  150NH IND  pkg L_TLM117513Q-151QL_11X7-5XA  page 196
  1  \1\  BI  = SW_PVDDCR_CPU0_P0_SW6
  2  \2\  BI  = IND_CPU0_P0_CPL0
  3  \3\  BI  = IND_CPU0_P0_CPL6
  4  \4\  BI  = PVDDCR_CPU0_P0

PL71  Q_INDUCTOR  BLM18SN220TN1D/8000MA IND  pkg SMLF  page 192 : 1 = P12V_AUX ; 2 = SW_P12V_AUX_PVDD_33_S5_FLT
PL72  Q_INDUCTOR  1.5UH IND  pkg SMLF  page 192 : 1 = SW_PVDD_33_S5_SW ; 2 = PVDD_33_S5
PL77  Q_INDUCTOR  BLM18SN220TN1D/8000MA IND  pkg SMLF  page 209 : 1 = P12V_AUX ; 2 = SW_P12V_AUX_PVDD18_S5_P0_FLT
PL78  Q_INDUCTOR  1.0UH/18A IND  pkg SMLF  page 209 : 1 = SW_PVDD18_S5_P0_SW ; 2 = PVDD18_S5_P0
PL6000  Q_INDUCTOR  3.3UH/6A IND  pkg SMLF  page 269 : 1 = SW_P1V8_AUX_PH ; 2 = P1V8_AUX
PL6001  Q_INDUCTOR  2.2UH IND  pkg SMLF  page 270 : 1 = SW_P1V2_AUX_PH ; 2 = P1V2_AUX
PL6002  Q_INDUCTOR  BLM18SN220TN1D/8000MA IND  pkg SMLF  page 269 : 1 = P12V_AUX ; 2 = SW_P12V_AUX_P1V8_AUX_FLT
PL6003  Q_INDUCTOR  BLM18SN220TN1D/8000MA IND  pkg SMLF  page 270 : 1 = P12V_AUX ; 2 = SW_P12V_AUX_P1V2_AUX_FLT
PL6500  Q_INDUCTOR  100NH/16A IND  pkg SMLF  page 360 : 1 = P12V_AUX ; 2 = SW_P12V_AUX_P1V8_RETIMER_CPU0_FLT
PL6501  Q_INDUCTOR  1UH IND  pkg SMLF  page 360 : 1 = SW_P1V8_RETIMER_CPU0_SW ; 2 = P1V8_CPU0_RT_1D
PL6502  Q_INDUCTOR  1UH IND  pkg SMLF  page 361 : 1 = SW_P1V8_RETIMER_CPU1_SW ; 2 = P1V8_CPU1_RT_1D
PL6503  Q_INDUCTOR  100NH/16A IND  pkg SMLF  page 361 : 1 = P12V_AUX ; 2 = SW_P12V_AUX_P1V8_RETIMER_CPU1_FLT
PL6504  Q_INDUCTOR  100NH/16A IND  pkg SMLF  page 363 : 1 = SW_P12V_AUX_P0V9_RETIMER_CPU0_FLT ; 2 = P12V_AUX
PL6505  Q_INDUCTOR  120NH/69A IND  pkg SMLF  page 363 : 1 = SW_P0V9_RETIMER_CPU0_SW1 ; 2 = P0V9_CPU0_RT_2D
PL6506  Q_INDUCTOR  120NH/69A IND  pkg SMLF  page 363 : 1 = SW_P0V9_RETIMER_CPU0_SW2 ; 2 = P0V9_CPU0_RT_2D
PL6510  Q_INDUCTOR  100NH/16A IND  pkg SMLF  page 365 : 1 = SW_P12V_AUX_P0V9_RETIMER_CPU1_FLT ; 2 = P12V_AUX
PL6511  Q_INDUCTOR  120NH/69A IND  pkg SMLF  page 365 : 1 = SW_P0V9_RETIMER_CPU1_SW1 ; 2 = P0V9_CPU1_RT_2D
PL6512  Q_INDUCTOR  120NH/69A IND  pkg SMLF  page 365 : 1 = SW_P0V9_RETIMER_CPU1_SW2 ; 2 = P0V9_CPU1_RT_2D
PL8045  Q_INDUCTOR  100NH/16A IND  pkg SMLF  page 190 : 1 = P12V_AUX ; 2 = SW_P3V3_AUX_FLT
PL8064  Q_INDUCTOR  BLM18SN220TN1D/8000MA IND  pkg SMLF  page 189 : 1 = P12V_AUX ; 2 = SW_P5V_AUX_FLT
PL8065  Q_INDUCTOR  4.7UH IND  pkg SMLF  page 189 : 1 = SW_P5V_AUX_SW ; 2 = P5V_AUX
PL8066  Q_INDUCTOR  1.5UH/53A IND  pkg SMLF  page 190 : 1 = SW_P3V3_AUX_SW ; 2 = P3V3_AUX

PPQ1  MOSFET_NCH_1D3S  PSMNR58-30YLH IC  pkg SOT1023  page 266
  1  \1\  BI  = P12V_AUX
  2  \2\  BI  = P12V_AUX
  3  \3\  BI  = P12V_AUX
  4  \4\  IN  = P12V_HSC_GATE_G5
  5  \5\  BI  = P12V_MAIN_R

PPQ2  MOSFET_NCH_1D3S  PSMNR58-30YLH IC  pkg SOT1023  page 266
  1  \1\  BI  = P12V_AUX
  2  \2\  BI  = P12V_AUX
  3  \3\  BI  = P12V_AUX
  4  \4\  IN  = P12V_HSC_GATE_G6
  5  \5\  BI  = P12V_MAIN_R

PPQ5  MOSFET_NCH_1D3S  PSMNR58-30YLH IC  pkg SOT1023  page 266
  1  \1\  BI  = P12V_AUX
  2  \2\  BI  = P12V_AUX
  3  \3\  BI  = P12V_AUX
  4  \4\  IN  = P12V_HSC_GATE_G1
  5  \5\  BI  = P12V_MAIN_R

PPQ6  MOSFET_NCH_1D3S  PSMNR58-30YLH IC  pkg SOT1023  page 266
  1  \1\  BI  = P12V_AUX
  2  \2\  BI  = P12V_AUX
  3  \3\  BI  = P12V_AUX
  4  \4\  IN  = P12V_HSC_GATE_G2
  5  \5\  BI  = P12V_MAIN_R

PPQ7  MOSFET_NCH_1D3S  PSMNR58-30YLH IC  pkg SOT1023  page 266
  1  \1\  BI  = P12V_AUX
  2  \2\  BI  = P12V_AUX
  3  \3\  BI  = P12V_AUX
  4  \4\  IN  = P12V_HSC_GATE_G3
  5  \5\  BI  = P12V_MAIN_R

PPQ8  MOSFET_NCH_1D3S  PSMNR58-30YLH IC  pkg SOT1023  page 266
  1  \1\  BI  = P12V_AUX
  2  \2\  BI  = P12V_AUX
  3  \3\  BI  = P12V_AUX
  4  \4\  IN  = P12V_HSC_GATE_G4
  5  \5\  BI  = P12V_MAIN_R

PPQ9  MOSFET_NCH_1D3S  PSMNR58-30YLH IC  pkg SOT1023  page 266
  1  \1\  BI  = P12V_AUX
  2  \2\  BI  = P12V_AUX
  3  \3\  BI  = P12V_AUX
  4  \4\  IN  = MB0_CM_GATE_G0
  5  \5\  BI  = P12V_MAIN_R_0

PQ10  MOSFET_PCH_GDS_ESD_PROTECTED  PJA3415AE IC  pkg SOT23_GDSXC  page 200
  D  D  BI  = PVDDCR_CPU1_P0_EN1_ADDR_CFG
  G  G  IN  = PVDDIO_P0_EN_G
  S  S  BI  = P3V3_AUX

PQ11  MOSFET_PCH_GDS_ESD_PROTECTED  PJA3415AE IC  pkg SOT23_GDSXC  page 210
  D  D  BI  = PVDDCR_SOC_P1_EN//ADDR_CFG
  G  G  IN  = PVDDCR_SOC_P1_EN_GD
  S  S  BI  = P3V3_AUX

PQ12  MOSFET_PCH_GDS_ESD_PROTECTED  PJA3415AE IC  pkg SOT23_GDSXC  page 217
  D  D  BI  = PVDDCR_CPU1_P1_EN1_ADDR_CFG
  G  G  IN  = PVDDIO_P1_EN_G
  S  S  BI  = P3V3_AUX

PQ13  MOSFET_PCH_GDS_ESD_PROTECTED  PJA3415AE IC  pkg SOT23_GDSXC  page 193
  D  D  BI  = PVDDCR_SOC_P0_EN//ADDR_CFG
  G  G  IN  = PVDDCR_SOC_P0_EN_GD
  S  S  BI  = P3V3_AUX

PQ14  MOSFET_N  BSS138K IC  pkg SMLF  page 200
  D  DRAIN  OUT  = PVDDIO_P0_EN_G
  G  GATE  IN  = PVDDIO_P0_EN_R
  S  SOURCE  BI  = GND

PQ15  MOSFET_N  BSS138K IC  pkg SMLF  page 210
  D  DRAIN  OUT  = PVDDCR_SOC_P1_EN_GD
  G  GATE  IN  = PVDDCR_SOC_P1_EN_RC
  S  SOURCE  BI  = GND

PQ16  MOSFET_N  BSS138K IC  pkg SMLF  page 217
  D  DRAIN  OUT  = PVDDIO_P1_EN_G
  G  GATE  IN  = PVDDIO_P1_EN_R
  S  SOURCE  BI  = GND
